# S9S_MB_2U (Grand Teton) — schematic netlist excerpt (pin names and nets, part order shuffled) for the footprints in the layout excerpt that follows; sources: Cadence DE-HDL packaged netlist, KiCad conversion of 03242023_DA0F0TMBIJ0_F0T_Motherboard_J_brd_V01_OCP.brd

R1123  Q_RES  1K 1% EMPTY  pkg 0402LF  page 158 : A = P3V3_AUX ; B = PD_SMB_OCP1_HP_ADD2

Q70  MOSFET_NCH_DUAL  PJT138K IC  pkg SOT363XD  page 148
  S1  = GND
  G1  = FM_SWB_BIC_READY_N
  D2  = FM_SWB_BIC_READY_ISO_N
  S2  = GND
  G2  = FM_SWB_BIC_READY
  D1  = FM_SWB_BIC_READY

(kicad_pcb
	(version 20260206)
	(generator "pcbnew")
	(generator_version "10.0")
	(general
		(thickness 1.6)
		(legacy_teardrops no)
	)
	(paper "A4")
	(title_block
		(title "03242023_DA0F0TMBIJ0_F0T_Motherboard_J_brd_V01_OCP.brd")
		(comment 1 "Grand Teton / footprints 1693-1694 of 6105")
	)
	(layers
		(0 "F.Cu" signal "TOP")
		(4 "In1.Cu" signal "GND")
		(6 "In2.Cu" signal "IN1")
		(8 "In3.Cu" signal "GND1")
		(10 "In4.Cu" signal "IN2")
		(12 "In5.Cu" signal "GND2")
		(14 "In6.Cu" signal "IN3")
		(16 "In7.Cu" signal "GND3")
		(18 "In8.Cu" signal "VCC")
		(20 "In9.Cu" signal "VCC1")
		(22 "In10.Cu" signal "GND4")
		(24 "In11.Cu" signal "IN4")
		(26 "In12.Cu" signal "GND5")
		(28 "In13.Cu" signal "IN5")
		(30 "In14.Cu" signal "GND6")
		(32 "In15.Cu" signal "IN6")
		(34 "In16.Cu" signal "GND7")
		(2 "B.Cu" signal "BOTTOM")
		(9 "F.Adhes" user "F.Adhesive")
		(11 "B.Adhes" user "B.Adhesive")
		(13 "F.Paste" user "Package Geometry/Pastemask Top")
		(15 "B.Paste" user "Package Geometry/Pastemask Bottom")
		(5 "F.SilkS" user "Ref Des/Silkscreen Top")
		(7 "B.SilkS" user "Ref Des/Silkscreen Bottom")
		(1 "F.Mask" user "Board Geometry/Soldermask Top")
		(3 "B.Mask" user "Board Geometry/Soldermask Bottom")
		(17 "Dwgs.User" user "User.Drawings")
		(19 "Cmts.User" user "User.Comments")
		(21 "Eco1.User" user "User.Eco1")
		(23 "Eco2.User" user "User.Eco2")
		(25 "Edge.Cuts" user "Board Geometry/Outline")
		(27 "Margin" user)
		(31 "F.CrtYd" user "Package Geometry/Place Bound Top")
		(29 "B.CrtYd" user "Package Geometry/Place Bound Bottom")
		(35 "F.Fab" user "Ref Des/Assembly Top")
		(33 "B.Fab" user "Ref Des/Assembly Bottom")
	)
	(footprint ""
		(layer "F.Cu")
		(at 447.482214 -117.193822)
		(property "Reference" "R1123"
			(at 0 0 0)
			(layer "F.SilkS")
			(hide yes)
			(effects
				(font
					(size 1.27 1.27)
				)
			)
		)
		(property "Value" ""
			(at 0 0 0)
			(layer "F.Fab")
			(effects
				(font
					(size 1.27 1.27)
				)
			)
		)
		(duplicate_pad_numbers_are_jumpers no)
		(fp_line
			(start -0.7874 -0.4064)
			(end 0.7874 -0.4064)
			(stroke
				(width 0.1524)
				(type default)
			)
			(layer "F.SilkS")
		)
		(fp_line
			(start -0.7874 0.4064)
			(end -0.7874 -0.4064)
			(stroke
				(width 0.1524)
				(type default)
			)
			(layer "F.SilkS")
		)
		(fp_line
			(start 0.7874 -0.4064)
			(end 0.7874 0.4064)
			(stroke
				(width 0.1524)
				(type default)
			)
			(layer "F.SilkS")
		)
		(fp_line
			(start 0.7874 0.4064)
			(end -0.7874 0.4064)
			(stroke
				(width 0.1524)
				(type default)
			)
			(layer "F.SilkS")
		)
		(fp_line
			(start -0.67945 -0.305054)
			(end -0.12065 -0.305054)
			(stroke
				(width 0.1)
				(type default)
			)
			(layer "F.Fab")
		)
		(fp_line
			(start -0.67945 0.3048)
			(end -0.67945 -0.305054)
			(stroke
				(width 0.1)
				(type default)
			)
			(layer "F.Fab")
		)
		(fp_line
			(start -0.12065 -0.305054)
			(end -0.12065 -0.2794)
			(stroke
				(width 0.1)
				(type default)
			)
			(layer "F.Fab")
		)
		(fp_line
			(start -0.12065 -0.2794)
			(end 0.12065 -0.2794)
			(stroke
				(width 0.1)
				(type default)
			)
			(layer "F.Fab")
		)
		(fp_line
			(start -0.12065 0.2794)
			(end -0.12065 0.3048)
			(stroke
				(width 0.1)
				(type default)
			)
			(layer "F.Fab")
		)
		(fp_line
			(start -0.12065 0.3048)
			(end -0.67945 0.3048)
			(stroke
				(width 0.1)
				(type default)
			)
			(layer "F.Fab")
		)
		(fp_line
			(start 0.120396 0.2794)
			(end -0.12065 0.2794)
			(stroke
				(width 0.1)
				(type default)
			)
			(layer "F.Fab")
		)
		(fp_line
			(start 0.120396 0.3048)
			(end 0.120396 0.2794)
			(stroke
				(width 0.1)
				(type default)
			)
			(layer "F.Fab")
		)
		(fp_line
			(start 0.12065 -0.3048)
			(end 0.67945 -0.3048)
			(stroke
				(width 0.1)
				(type default)
			)
			(layer "F.Fab")
		)
		(fp_line
			(start 0.12065 -0.2794)
			(end 0.12065 -0.3048)
			(stroke
				(width 0.1)
				(type default)
			)
			(layer "F.Fab")
		)
		(fp_line
			(start 0.67945 -0.3048)
			(end 0.67945 0.3048)
			(stroke
				(width 0.1)
				(type default)
			)
			(layer "F.Fab")
		)
		(fp_line
			(start 0.67945 0.3048)
			(end 0.120396 0.3048)
			(stroke
				(width 0.1)
				(type default)
			)
			(layer "F.Fab")
		)
		(pad "1" smd circle
			(at -0.40005 0)
			(size 0 0)
			(layers "F.Cu" "F.Mask" "F.Paste")
			(net "P3V3_AUX")
		)
		(pad "2" smd circle
			(at 0.40005 0)
			(size 0 0)
			(layers "F.Cu" "F.Mask" "F.Paste")
			(net "PD_SMB_OCP1_HP_ADD2")
		)
	)
	(footprint ""
		(layer "F.Cu")
		(at 428.179992 -391.505948)
		(property "Reference" "Q70"
			(at 0.462788 -1.93675 0)
			(unlocked yes)
			(layer "F.SilkS")
			(effects
				(font
					(size 0.7874 0.5842)
					(thickness 0.1524)
				)
				(justify left)
			)
		)
		(property "Value" ""
			(at 0 0 0)
			(layer "F.Fab")
			(effects
				(font
					(size 1.27 1.27)
				)
			)
		)
		(duplicate_pad_numbers_are_jumpers no)
		(fp_line
			(start -1.332738 -1.100074)
			(end -0.4826 -1.100074)
			(stroke
				(width 0.1524)
				(type default)
			)
			(layer "F.SilkS")
		)
		(fp_line
			(start -1.332738 1.100074)
			(end -1.332738 -1.100074)
			(stroke
				(width 0.1524)
				(type default)
			)
			(layer "F.SilkS")
		)
		(fp_line
			(start -0.4826 -1.100074)
			(end 0 -0.541274)
			(stroke
				(width 0.1524)
				(type default)
			)
			(layer "F.SilkS")
		)
		(fp_line
			(start 0 -0.541274)
			(end 0.4826 -1.100074)
			(stroke
				(width 0.1524)
				(type default)
			)
			(layer "F.SilkS")
		)
		(fp_line
			(start 0.4826 -1.100074)
			(end 1.332738 -1.100074)
			(stroke
				(width 0.1524)
				(type default)
			)
			(layer "F.SilkS")
		)
		(fp_line
			(start 1.332738 -1.100074)
			(end 1.332738 1.100074)
			(stroke
				(width 0.1524)
				(type default)
			)
			(layer "F.SilkS")
		)
		(fp_line
			(start 1.332738 1.100074)
			(end -1.332738 1.100074)
			(stroke
				(width 0.1524)
				(type default)
			)
			(layer "F.SilkS")
		)
		(fp_poly
			(pts
				(xy -0.613918 -2.146808) (xy -0.964946 -1.444752) (xy -1.315974 -2.146808)
			)
			(stroke
				(width 0)
				(type default)
			)
			(fill yes)
			(layer "F.SilkS")
		)
		(fp_line
			(start -0.674878 -1.100074)
			(end 0.674878 -1.100074)
			(stroke
				(width 0.1)
				(type default)
			)
			(layer "F.Fab")
		)
		(fp_line
			(start -0.674878 1.100074)
			(end -0.674878 -1.100074)
			(stroke
				(width 0.1)
				(type default)
			)
			(layer "F.Fab")
		)
		(fp_line
			(start 0.674878 -1.100074)
			(end 0.674878 1.100074)
			(stroke
				(width 0.1)
				(type default)
			)
			(layer "F.Fab")
		)
		(fp_line
			(start 0.674878 1.100074)
			(end -0.674878 1.100074)
			(stroke
				(width 0.1)
				(type default)
			)
			(layer "F.Fab")
		)
		(fp_poly
			(pts
				(xy -2.2352 -0.298958) (xy -2.2352 -1.001014) (xy -1.533144 -0.649986)
			)
			(stroke
				(width 0)
				(type default)
			)
			(fill yes)
			(layer "F.Fab")
		)
		(pad "1" smd rect
			(at -0.94996 -0.649986 90)
			(size 0.4318 0.508)
			(layers "F.Cu" "F.Mask" "F.Paste")
			(net "GND")
		)
		(pad "2" smd rect
			(at -0.94996 0 90)
			(size 0.4318 0.508)
			(layers "F.Cu" "F.Mask" "F.Paste")
			(net "FM_SWB_BIC_READY_N")
		)
		(pad "3" smd rect
			(at -0.94996 0.649986 90)
			(size 0.4318 0.508)
			(layers "F.Cu" "F.Mask" "F.Paste")
			(net "FM_SWB_BIC_READY_ISO_N")
		)
		(pad "4" smd rect
			(at 0.94996 0.649986 90)
			(size 0.4318 0.508)
			(layers "F.Cu" "F.Mask" "F.Paste")
			(net "GND")
		)
		(pad "5" smd rect
			(at 0.94996 0 90)
			(size 0.4318 0.508)
			(layers "F.Cu" "F.Mask" "F.Paste")
			(net "FM_SWB_BIC_READY")
		)
		(pad "6" smd rect
			(at 0.94996 -0.649986 90)
			(size 0.4318 0.508)
			(layers "F.Cu" "F.Mask" "F.Paste")
			(net "FM_SWB_BIC_READY")
		)
	)
)
